# S9S_MB_2U (Grand Teton) — schematic netlist excerpt (pin names and nets, part order shuffled) for the footprints in the layout excerpt that follows; sources: Cadence DE-HDL packaged netlist, KiCad conversion of 03242023_DA0F0TMBIJ0_F0T_Motherboard_J_brd_V01_OCP.brd

J13  SCONN288_ADR50017P130CC  SCONN288_ADR50017-P130CC IO  pkg DDR288S_1-1VXB  page 94
  VIN_BULK0  = P12V_S3_AUX_CPU0_NVDIMM
  RFU0  = TP_CHG_CPU0_DIMM1_FRU_0
  VIN_MGMT  = P3V3_AUX
  HSCL  = I3C_SPD_DDREFGH_CPU0_LVC1_SCL_4
  HSDA  = I3C_SPD_DDREFGH_CPU0_LVC1_SDA
  VSS0  = GND
  DQ0_A  = M_G_CPU0_SA_DQ<0>
  VSS1  = GND
  DQ1_A  = M_G_CPU0_SA_DQ<1>
  VSS2  = GND
  DQS0_A_T  = M_G_CPU0_SA_DQS_DP<0>
  DQS0_A_C  = M_G_CPU0_SA_DQS_DN<0>
  VSS3  = GND
  DQ4_A  = M_G_CPU0_SA_DQ<4>
  VSS4  = GND
  DQ5_A  = M_G_CPU0_SA_DQ<5>
  VSS5  = GND
  DQ8_A  = M_G_CPU0_SA_DQ<8>
  VSS6  = GND
  DQ9_A  = M_G_CPU0_SA_DQ<9>
  VSS7  = GND
  DQS1_A_T  = M_G_CPU0_SA_DQS_DP<1>
  DQS1_A_C  = M_G_CPU0_SA_DQS_DN<1>
  VSS8  = GND
  DQ12_A  = M_G_CPU0_SA_DQ<12>
  VSS9  = GND
  DQ13_A  = M_G_CPU0_SA_DQ<13>
  VSS10  = GND
  DQ16_A  = M_G_CPU0_SA_DQ<16>
  VSS11  = GND
  DQ17_A  = M_G_CPU0_SA_DQ<17>
  VSS12  = GND
  DQS2_A_T  = M_G_CPU0_SA_DQS_DP<2>
  DQS2_A_C  = M_G_CPU0_SA_DQS_DN<2>
  VSS13  = GND
  DQ20_A  = M_G_CPU0_SA_DQ<20>
  VSS14  = GND
  DQ21_A  = M_G_CPU0_SA_DQ<21>
  VSS15  = GND
  DQ24_A  = M_G_CPU0_SA_DQ<24>
  VSS16  = GND
  DQ25_A  = M_G_CPU0_SA_DQ<25>
  VSS17  = GND
  DQS3_A_T  = M_G_CPU0_SA_DQS_DP<3>
  DQS3_A_C  = M_G_CPU0_SA_DQS_DN<3>
  VSS18  = GND
  DQ28_A  = M_G_CPU0_SA_DQ<28>
  VSS19  = GND
  DQ29_A  = M_G_CPU0_SA_DQ<29>
  VSS20  = GND
  CB0_A  = M_G_CPU0_SA_CB<0>
  VSS21  = GND
  CB1_A  = M_G_CPU0_SA_CB<1>
  VSS22  = GND
  DQS4_A_T  = M_G_CPU0_SA_DQS_DP<4>
  DQS4_A_C  = M_G_CPU0_SA_DQS_DN<4>
  VSS23  = GND
  CB4_A  = M_G_CPU0_SA_CB<4>
  VSS24  = GND
  CB5_A  = M_G_CPU0_SA_CB<5>
  VSS25  = GND
  ALERT_N  = M_G_CPU0_ALERT_N
  VSS26  = GND
  CS0_A_N  = M_G_CPU0_SA_CS_N<0>
  VSS27  = GND
  CA0_A  = M_G_CPU0_SA_CA<0>
  VSS28  = GND
  CA2_A  = M_G_CPU0_SA_CA<2>
  VSS29  = GND
  CA4_A  = M_G_CPU0_SA_CA<4>
  VSS30  = GND
  CA6_A  = M_G_CPU0_SA_CA<6>
  VSS31  = GND
  PAR_A  = M_G_CPU0_SA_PAR
  VSS32  = GND
  CA0_B  = M_G_CPU0_SB_CA<0>
  VSS33  = GND
  CA2_B  = M_G_CPU0_SB_CA<2>
  VSS34  = GND
  CA4_B  = M_G_CPU0_SB_CA<4>
  VSS35  = GND
  CA6_B  = M_G_CPU0_SB_CA<6>
  VSS36  = GND
  CS0_B_N  = M_G_CPU0_SB_CS_N<0>
  VSS37  = GND
  \lbd||rsp_a_n\  = M_G_CPU0_SA_RSP<0>
  \lbs||rsp_b_n\  = M_G_CPU0_SB_RSP<0>
  VSS38  = GND
  CB4_B  = M_G_CPU0_SB_CB<4>
  VSS39  = GND
  CB5_B  = M_G_CPU0_SB_CB<5>
  VSS40  = GND
  \dqs9_b_t||tdqs9_b_t||dbi4_b_n\  = M_G_CPU0_SB_DQS_DP<9>
  \dqs9_b_c||tdqs9_b_c\  = M_G_CPU0_SB_DQS_DN<9>
  VSS41  = GND
  CB0_B  = M_G_CPU0_SB_CB<0>
  VSS42  = GND
  CB1_B  = M_G_CPU0_SB_CB<1>
  VSS43  = GND
  DQ0_B  = M_G_CPU0_SB_DQ<0>
  VSS44  = GND
  DQ1_B  = M_G_CPU0_SB_DQ<1>
  VSS45  = GND
  DQS0_B_T  = M_G_CPU0_SB_DQS_DP<0>
  DQS0_B_C  = M_G_CPU0_SB_DQS_DN<0>
  VSS46  = GND
  DQ4_B  = M_G_CPU0_SB_DQ<4>
  VSS47  = GND
  DQ5_B  = M_G_CPU0_SB_DQ<5>
  VSS48  = GND
  DQ8_B  = M_G_CPU0_SB_DQ<8>
  VSS49  = GND
  DQ9_B  = M_G_CPU0_SB_DQ<9>
  VSS50  = GND
  DQS1_B_T  = M_G_CPU0_SB_DQS_DP<1>
  DQS1_B_C  = M_G_CPU0_SB_DQS_DN<1>
  VSS51  = GND
  DQ12_B  = M_G_CPU0_SB_DQ<12>
  VSS52  = GND
  DQ13_B  = M_G_CPU0_SB_DQ<13>
  VSS53  = GND
  DQ16_B  = M_G_CPU0_SB_DQ<16>
  VSS54  = GND
  DQ17_B  = M_G_CPU0_SB_DQ<17>
  VSS55  = GND
  DQS2_B_T  = M_G_CPU0_SB_DQS_DP<2>
  DQS2_B_C  = M_G_CPU0_SB_DQS_DN<2>
  VSS56  = GND
  DQ20_B  = M_G_CPU0_SB_DQ<20>
  VSS57  = GND
  DQ21_B  = M_G_CPU0_SB_DQ<21>
  VSS58  = GND
  DQ24_B  = M_G_CPU0_SB_DQ<24>
  VSS59  = GND
  DQ25_B  = M_G_CPU0_SB_DQ<25>
  VSS60  = GND
  DQS3_B_T  = M_G_CPU0_SB_DQS_DP<3>
  DQS3_B_C  = M_G_CPU0_SB_DQS_DN<3>
  VSS61  = GND
  DQ28_B  = M_G_CPU0_SB_DQ<28>
  VSS62  = GND
  DQ29_B  = M_G_CPU0_SB_DQ<29>
  VSS63  = GND
  RFU1  = TP_CHG_CPU0_DIMM1_FRU_1
  VIN_BULK1  = P12V_S3_AUX_CPU0_NVDIMM
  VIN_BULK2  = P12V_S3_AUX_CPU0_NVDIMM
  \pwr_good||fail_n\  = PWRGD_CHG_CPU0_DIMM1
  HSA  = PD_CHG_CPU0_DIMM1_SAA
  RFU2  = TP_CHG_CPU0_DIMM1_FRU_2
  RFU3  = TP_CHG_CPU0_DIMM1_FRU_3
  VSS64  = GND
  DQ2_A  = M_G_CPU0_SA_DQ<2>
  VSS65  = GND
  DQ3_A  = M_G_CPU0_SA_DQ<3>
  VSS66  = GND
  \dqs5_a_c||tdqs5_a_c||dqs5_a_t||tdqs5_a_t\  = M_G_CPU0_SA_DQS_DN<5>
  \dqs5_a_t||tdqs5_a_t\  = M_G_CPU0_SA_DQS_DP<5>
  VSS67  = GND
  DQ6_A  = M_G_CPU0_SA_DQ<6>
  VSS68  = GND
  DQ7_A  = M_G_CPU0_SA_DQ<7>
  VSS69  = GND
  DQ10_A  = M_G_CPU0_SA_DQ<10>
  VSS70  = GND
  DQ11_A  = M_G_CPU0_SA_DQ<11>
  VSS71  = GND
  \dqs6_a_c||tdqs6_a_c||dqs6_a_t||tdqs6_a_t\  = M_G_CPU0_SA_DQS_DN<6>
  \dqs6_a_t||tdqs6_a_t\  = M_G_CPU0_SA_DQS_DP<6>
  VSS72  = GND
  DQ14_A  = M_G_CPU0_SA_DQ<14>
  VSS73  = GND
  DQ15_A  = M_G_CPU0_SA_DQ<15>
  VSS74  = GND
  DQ18_A  = M_G_CPU0_SA_DQ<18>
  VSS75  = GND
  DQ19_A  = M_G_CPU0_SA_DQ<19>
  VSS76  = GND
  \dqs7_a_c||tdqs7_a_c\  = M_G_CPU0_SA_DQS_DN<7>
  \dqs7_a_t||tdqs7_a_t\  = M_G_CPU0_SA_DQS_DP<7>
  VSS77  = GND
  DQ22_A  = M_G_CPU0_SA_DQ<22>
  VSS78  = GND
  DQ23_A  = M_G_CPU0_SA_DQ<23>
  VSS79  = GND
  DQ26_A  = M_G_CPU0_SA_DQ<26>
  VSS80  = GND
  DQ27_A  = M_G_CPU0_SA_DQ<27>
  VSS81  = GND
  \dqs8_a_c||tdqs8_a_c\  = M_G_CPU0_SA_DQS_DN<8>
  \dqs8_a_t||tdqs8_a_t\  = M_G_CPU0_SA_DQS_DP<8>
  VSS82  = GND
  DQ30_A  = M_G_CPU0_SA_DQ<30>
  VSS83  = GND
  DQ31_A  = M_G_CPU0_SA_DQ<31>
  VSS84  = GND
  CB2_A  = M_G_CPU0_SA_CB<2>
  VSS85  = GND
  CB3_A  = M_G_CPU0_SA_CB<3>
  VSS86  = GND
  \dqs9_a_c||tdqs9_a_c\  = M_G_CPU0_SA_DQS_DN<9>
  \dqs9_a_t||tdqs9_a_t\  = M_G_CPU0_SA_DQS_DP<9>
  VSS87  = GND
  CB6_A  = M_G_CPU0_SA_CB<6>
  VSS88  = GND
  CB7_A  = M_G_CPU0_SA_CB<7>
  VSS89  = GND
  RESET_N  = RST_M_GH_CPU0_FPGA_N
  VSS90  = GND
  CS1_A_N  = M_G_CPU0_SA_CS_N<1>
  VSS91  = GND
  CA1_A  = M_G_CPU0_SA_CA<1>
  VSS92  = GND
  CA3_A  = M_G_CPU0_SA_CA<3>
  VSS93  = GND
  CA5_A  = M_G_CPU0_SA_CA<5>
  VSS94  = GND
  CK_T  = M_G_CPU0_CLK_DP<0>
  CK_C  = M_G_CPU0_CLK_DN<0>
  VSS95  = GND
  RFU4  = TP_CHG_CPU0_DIMM1_FRU_4
  CA1_B  = M_G_CPU0_SB_CA<1>
  VSS96  = GND
  CA3_B  = M_G_CPU0_SB_CA<3>
  VSS97  = GND
  CA5_B  = M_G_CPU0_SB_CA<5>
  VSS98  = GND
  PAR_B  = M_G_CPU0_SB_PAR
  VSS99  = GND
  CS1_B_N  = M_G_CPU0_SB_CS_N<1>
  VSS100  = GND
  RFU5  = TP_CHG_CPU0_DIMM1_FRU_5
  RFU6  = TP_CHG_CPU0_DIMM1_FRU_6
  VSS101  = GND
  CB6_B  = M_G_CPU0_SB_CB<6>
  VSS102  = GND
  CB7_B  = M_G_CPU0_SB_CB<7>
  VSS103  = GND
  DQS4_B_C  = M_G_CPU0_SB_DQS_DN<4>
  DQS4_B_T  = M_G_CPU0_SB_DQS_DP<4>
  VSS104  = GND
  CB2_B  = M_G_CPU0_SB_CB<2>
  VSS105  = GND
  CB3_B  = M_G_CPU0_SB_CB<3>
  VSS106  = GND
  DQ2_B  = M_G_CPU0_SB_DQ<2>
  VSS107  = GND
  DQ3_B  = M_G_CPU0_SB_DQ<3>
  VSS108  = GND
  \dqs5_b_c||tdqs5_b_c\  = M_G_CPU0_SB_DQS_DN<5>
  \dqs5_b_t||tdqs5_b_t\  = M_G_CPU0_SB_DQS_DP<5>
  VSS109  = GND
  DQ6_B  = M_G_CPU0_SB_DQ<6>
  VSS110  = GND
  DQ7_B  = M_G_CPU0_SB_DQ<7>
  VSS111  = GND
  DQ10_B  = M_G_CPU0_SB_DQ<10>
  VSS112  = GND
  DQ11_B  = M_G_CPU0_SB_DQ<11>
  VSS113  = GND
  \dqs6_b_c||tdqs6_b_c\  = M_G_CPU0_SB_DQS_DN<6>
  \dqs6_b_t||tdqs6_b_t\  = M_G_CPU0_SB_DQS_DP<6>
  VSS114  = GND
  DQ14_B  = M_G_CPU0_SB_DQ<14>
  VSS115  = GND
  DQ15_B  = M_G_CPU0_SB_DQ<15>
  VSS116  = GND
  DQ18_B  = M_G_CPU0_SB_DQ<18>
  VSS117  = GND
  DQ19_B  = M_G_CPU0_SB_DQ<19>
  VSS118  = GND
  \dqs7_b_c||tdqs7_b_c\  = M_G_CPU0_SB_DQS_DN<7>
  \dqs7_b_t||tdqs7_b_t\  = M_G_CPU0_SB_DQS_DP<7>
  VSS119  = GND
  DQ22_B  = M_G_CPU0_SB_DQ<22>
  VSS120  = GND
  DQ23_B  = M_G_CPU0_SB_DQ<23>
  VSS121  = GND
  DQ26_B  = M_G_CPU0_SB_DQ<26>
  VSS122  = GND
  DQ27_B  = M_G_CPU0_SB_DQ<27>
  VSS123  = GND
  \dqs8_b_c||tdqs8_b_c\  = M_G_CPU0_SB_DQS_DN<8>
  \dqs8_b_t||tdqs8_b_t\  = M_G_CPU0_SB_DQS_DP<8>
  VSS124  = GND
  DQ30_B  = M_G_CPU0_SB_DQ<30>
  VSS125  = GND
  DQ31_B  = M_G_CPU0_SB_DQ<31>
  VSS126  = GND
  G1  = GND
  G2  = GND
  G3  = GND

(kicad_pcb
	(version 20260206)
	(generator "pcbnew")
	(generator_version "10.0")
	(general
		(thickness 1.6)
		(legacy_teardrops no)
	)
	(paper "A4")
	(title_block
		(title "03242023_DA0F0TMBIJ0_F0T_Motherboard_J_brd_V01_OCP.brd")
		(comment 1 "Grand Teton / footprint 1368 of 6105 (J13), pads 92-137 of 291")
	)
	(layers
		(0 "F.Cu" signal "TOP")
		(4 "In1.Cu" signal "GND")
		(6 "In2.Cu" signal "IN1")
		(8 "In3.Cu" signal "GND1")
		(10 "In4.Cu" signal "IN2")
		(12 "In5.Cu" signal "GND2")
		(14 "In6.Cu" signal "IN3")
		(16 "In7.Cu" signal "GND3")
		(18 "In8.Cu" signal "VCC")
		(20 "In9.Cu" signal "VCC1")
		(22 "In10.Cu" signal "GND4")
		(24 "In11.Cu" signal "IN4")
		(26 "In12.Cu" signal "GND5")
		(28 "In13.Cu" signal "IN5")
		(30 "In14.Cu" signal "GND6")
		(32 "In15.Cu" signal "IN6")
		(34 "In16.Cu" signal "GND7")
		(2 "B.Cu" signal "BOTTOM")
		(9 "F.Adhes" user "F.Adhesive")
		(11 "B.Adhes" user "B.Adhesive")
		(13 "F.Paste" user "Package Geometry/Pastemask Top")
		(15 "B.Paste" user "Package Geometry/Pastemask Bottom")
		(5 "F.SilkS" user "Ref Des/Silkscreen Top")
		(7 "B.SilkS" user "Ref Des/Silkscreen Bottom")
		(1 "F.Mask" user "Board Geometry/Soldermask Top")
		(3 "B.Mask" user "Board Geometry/Soldermask Bottom")
		(17 "Dwgs.User" user "User.Drawings")
		(19 "Cmts.User" user "User.Comments")
		(21 "Eco1.User" user "User.Eco1")
		(23 "Eco2.User" user "User.Eco2")
		(25 "Edge.Cuts" user "Board Geometry/Outline")
		(27 "Margin" user)
		(31 "F.CrtYd" user "Package Geometry/Place Bound Top")
		(29 "B.CrtYd" user "Package Geometry/Place Bound Bottom")
		(35 "F.Fab" user "Ref Des/Assembly Top")
		(33 "B.Fab" user "Ref Des/Assembly Bottom")
	)
	(footprint ""
		(layer "F.Cu")
		(at 446.522348 -258.091686)
		(property "Reference" "J13"
			(at -3.683 -81.702148 0)
			(unlocked yes)
			(layer "F.SilkS")
			(effects
				(font
					(size 0.7874 0.5842)
					(thickness 0.1524)
				)
				(justify left)
			)
		)
		(property "Value" ""
			(at 0 0 0)
			(layer "F.Fab")
			(effects
				(font
					(size 1.27 1.27)
				)
			)
		)
		(duplicate_pad_numbers_are_jumpers no)
		(pad "92" smd rect
			(at -2.050034 19.12493 270)
			(size 0.519938 1.4986)
			(layers "F.Cu" "F.Mask" "F.Paste")
			(net "GND")
		)
		(pad "93" smd rect
			(at -2.050034 19.975068 270)
			(size 0.519938 1.4986)
			(layers "F.Cu" "F.Mask" "F.Paste")
			(net "M_G_CPU0_SB_DQS_DP<9>")
		)
		(pad "94" smd rect
			(at -2.050034 20.824952 270)
			(size 0.519938 1.4986)
			(layers "F.Cu" "F.Mask" "F.Paste")
			(net "M_G_CPU0_SB_DQS_DN<9>")
		)
		(pad "95" smd rect
			(at -2.050034 21.67509 270)
			(size 0.519938 1.4986)
			(layers "F.Cu" "F.Mask" "F.Paste")
			(net "GND")
		)
		(pad "96" smd rect
			(at -2.050034 22.524974 270)
			(size 0.519938 1.4986)
			(layers "F.Cu" "F.Mask" "F.Paste")
			(net "M_G_CPU0_SB_CB<0>")
		)
		(pad "97" smd rect
			(at -2.050034 23.375112 270)
			(size 0.519938 1.4986)
			(layers "F.Cu" "F.Mask" "F.Paste")
			(net "GND")
		)
		(pad "98" smd rect
			(at -2.050034 24.224996 270)
			(size 0.519938 1.4986)
			(layers "F.Cu" "F.Mask" "F.Paste")
			(net "M_G_CPU0_SB_CB<1>")
		)
		(pad "99" smd rect
			(at -2.050034 25.07488 270)
			(size 0.519938 1.4986)
			(layers "F.Cu" "F.Mask" "F.Paste")
			(net "GND")
		)
		(pad "100" smd rect
			(at -2.050034 25.925018 270)
			(size 0.519938 1.4986)
			(layers "F.Cu" "F.Mask" "F.Paste")
			(net "M_G_CPU0_SB_DQ<0>")
		)
		(pad "101" smd rect
			(at -2.050034 26.774902 270)
			(size 0.519938 1.4986)
			(layers "F.Cu" "F.Mask" "F.Paste")
			(net "GND")
		)
		(pad "102" smd rect
			(at -2.050034 27.62504 270)
			(size 0.519938 1.4986)
			(layers "F.Cu" "F.Mask" "F.Paste")
			(net "M_G_CPU0_SB_DQ<1>")
		)
		(pad "103" smd rect
			(at -2.050034 28.474924 270)
			(size 0.519938 1.4986)
			(layers "F.Cu" "F.Mask" "F.Paste")
			(net "GND")
		)
		(pad "104" smd rect
			(at -2.050034 29.325062 270)
			(size 0.519938 1.4986)
			(layers "F.Cu" "F.Mask" "F.Paste")
			(net "M_G_CPU0_SB_DQS_DP<0>")
		)
		(pad "105" smd rect
			(at -2.050034 30.174946 270)
			(size 0.519938 1.4986)
			(layers "F.Cu" "F.Mask" "F.Paste")
			(net "M_G_CPU0_SB_DQS_DN<0>")
		)
		(pad "106" smd rect
			(at -2.050034 31.025084 270)
			(size 0.519938 1.4986)
			(layers "F.Cu" "F.Mask" "F.Paste")
			(net "GND")
		)
		(pad "107" smd rect
			(at -2.050034 31.874968 270)
			(size 0.519938 1.4986)
			(layers "F.Cu" "F.Mask" "F.Paste")
			(net "M_G_CPU0_SB_DQ<4>")
		)
		(pad "108" smd rect
			(at -2.050034 32.725106 270)
			(size 0.519938 1.4986)
			(layers "F.Cu" "F.Mask" "F.Paste")
			(net "GND")
		)
		(pad "109" smd rect
			(at -2.050034 33.57499 270)
			(size 0.519938 1.4986)
			(layers "F.Cu" "F.Mask" "F.Paste")
			(net "M_G_CPU0_SB_DQ<5>")
		)
		(pad "110" smd rect
			(at -2.050034 34.425128 270)
			(size 0.519938 1.4986)
			(layers "F.Cu" "F.Mask" "F.Paste")
			(net "GND")
		)
		(pad "111" smd rect
			(at -2.050034 35.275012 270)
			(size 0.519938 1.4986)
			(layers "F.Cu" "F.Mask" "F.Paste")
			(net "M_G_CPU0_SB_DQ<8>")
		)
		(pad "112" smd rect
			(at -2.050034 36.124896 270)
			(size 0.519938 1.4986)
			(layers "F.Cu" "F.Mask" "F.Paste")
			(net "GND")
		)
		(pad "113" smd rect
			(at -2.050034 36.975034 270)
			(size 0.519938 1.4986)
			(layers "F.Cu" "F.Mask" "F.Paste")
			(net "M_G_CPU0_SB_DQ<9>")
		)
		(pad "114" smd rect
			(at -2.050034 37.824918 270)
			(size 0.519938 1.4986)
			(layers "F.Cu" "F.Mask" "F.Paste")
			(net "GND")
		)
		(pad "115" smd rect
			(at -2.050034 38.675056 270)
			(size 0.519938 1.4986)
			(layers "F.Cu" "F.Mask" "F.Paste")
			(net "M_G_CPU0_SB_DQS_DP<1>")
		)
		(pad "116" smd rect
			(at -2.050034 39.52494 270)
			(size 0.519938 1.4986)
			(layers "F.Cu" "F.Mask" "F.Paste")
			(net "M_G_CPU0_SB_DQS_DN<1>")
		)
		(pad "117" smd rect
			(at -2.050034 40.375078 270)
			(size 0.519938 1.4986)
			(layers "F.Cu" "F.Mask" "F.Paste")
			(net "GND")
		)
		(pad "118" smd rect
			(at -2.050034 41.224962 270)
			(size 0.519938 1.4986)
			(layers "F.Cu" "F.Mask" "F.Paste")
			(net "M_G_CPU0_SB_DQ<12>")
		)
		(pad "119" smd rect
			(at -2.050034 42.0751 270)
			(size 0.519938 1.4986)
			(layers "F.Cu" "F.Mask" "F.Paste")
			(net "GND")
		)
		(pad "120" smd rect
			(at -2.050034 42.924984 270)
			(size 0.519938 1.4986)
			(layers "F.Cu" "F.Mask" "F.Paste")
			(net "M_G_CPU0_SB_DQ<13>")
		)
		(pad "121" smd rect
			(at -2.050034 43.775122 270)
			(size 0.519938 1.4986)
			(layers "F.Cu" "F.Mask" "F.Paste")
			(net "GND")
		)
		(pad "122" smd rect
			(at -2.050034 44.625006 270)
			(size 0.519938 1.4986)
			(layers "F.Cu" "F.Mask" "F.Paste")
			(net "M_G_CPU0_SB_DQ<16>")
		)
		(pad "123" smd rect
			(at -2.050034 45.47489 270)
			(size 0.519938 1.4986)
			(layers "F.Cu" "F.Mask" "F.Paste")
			(net "GND")
		)
		(pad "124" smd rect
			(at -2.050034 46.325028 270)
			(size 0.519938 1.4986)
			(layers "F.Cu" "F.Mask" "F.Paste")
			(net "M_G_CPU0_SB_DQ<17>")
		)
		(pad "125" smd rect
			(at -2.050034 47.174912 270)
			(size 0.519938 1.4986)
			(layers "F.Cu" "F.Mask" "F.Paste")
			(net "GND")
		)
		(pad "126" smd rect
			(at -2.050034 48.02505 270)
			(size 0.519938 1.4986)
			(layers "F.Cu" "F.Mask" "F.Paste")
			(net "M_G_CPU0_SB_DQS_DP<2>")
		)
		(pad "127" smd rect
			(at -2.050034 48.874934 270)
			(size 0.519938 1.4986)
			(layers "F.Cu" "F.Mask" "F.Paste")
			(net "M_G_CPU0_SB_DQS_DN<2>")
		)
		(pad "128" smd rect
			(at -2.050034 49.725072 270)
			(size 0.519938 1.4986)
			(layers "F.Cu" "F.Mask" "F.Paste")
			(net "GND")
		)
		(pad "129" smd rect
			(at -2.050034 50.574956 270)
			(size 0.519938 1.4986)
			(layers "F.Cu" "F.Mask" "F.Paste")
			(net "M_G_CPU0_SB_DQ<20>")
		)
		(pad "130" smd rect
			(at -2.050034 51.425094 270)
			(size 0.519938 1.4986)
			(layers "F.Cu" "F.Mask" "F.Paste")
			(net "GND")
		)
		(pad "131" smd rect
			(at -2.050034 52.274978 270)
			(size 0.519938 1.4986)
			(layers "F.Cu" "F.Mask" "F.Paste")
			(net "M_G_CPU0_SB_DQ<21>")
		)
		(pad "132" smd rect
			(at -2.050034 53.125116 270)
			(size 0.519938 1.4986)
			(layers "F.Cu" "F.Mask" "F.Paste")
			(net "GND")
		)
		(pad "133" smd rect
			(at -2.050034 53.975 270)
			(size 0.519938 1.4986)
			(layers "F.Cu" "F.Mask" "F.Paste")
			(net "M_G_CPU0_SB_DQ<24>")
		)
		(pad "134" smd rect
			(at -2.050034 54.824884 270)
			(size 0.519938 1.4986)
			(layers "F.Cu" "F.Mask" "F.Paste")
			(net "GND")
		)
		(pad "135" smd rect
			(at -2.050034 55.675022 270)
			(size 0.519938 1.4986)
			(layers "F.Cu" "F.Mask" "F.Paste")
			(net "M_G_CPU0_SB_DQ<25>")
		)
		(pad "136" smd rect
			(at -2.050034 56.524906 270)
			(size 0.519938 1.4986)
			(layers "F.Cu" "F.Mask" "F.Paste")
			(net "GND")
		)
		(pad "137" smd rect
			(at -2.050034 57.375044 270)
			(size 0.519938 1.4986)
			(layers "F.Cu" "F.Mask" "F.Paste")
			(net "M_G_CPU0_SB_DQS_DP<3>")
		)
	)
)
